FILE_TYPE = MACRO_DRAWING;
SET COLOR_WIRE YELLOW;
SET COLOR_PROP ORANGE;
SET COLOR_DOT WHITE;
SET COLOR_ARC YELLOW;
SET COLOR_BODY GREEN;
SET COLOR_NOTE PURPLE;
SET PROP_DISPLAY VALUE;
SET PAGE_NUMBER P266;
FORCEADD UNIVERSAL_GND..1
(-7425 1775);
FORCEPROP 3 LASTPIN (-7425 1825) SIG_NAME T1_GND\g
J 0
(-7415 1835);
DISPLAY 0.659574 (-7415 1835);
PAINT MONO (-7415 1835);
DISPLAY INVISIBLE (-7415 1835);
FORCEPROP 1 LAST HDL_POWER T1_GND
J 1
(-7400 1700);
DISPLAY 0.872340 (-7400 1700);
PAINT GREEN (-7400 1700);
FORCEPROP 2 LAST CDS_LIB pure_quanta_power
J 0
(-7425 1775);
DISPLAY INVISIBLE (-7425 1775);
FORCEPROP 1 LAST PATH I1
J 0
(-7350 1775);
DISPLAY 0.872340 (-7350 1775);
PAINT AQUA (-7350 1775);
DISPLAY INVISIBLE (-7350 1775);
FORCEADD TP_TDR_4P_FTS..1
(-7000 5000);
FORCEPROP 1 LAST LOCATION X9003
J 0
(-7125 5280);
DISPLAY 0.723404 (-7125 5280);
PAINT GREEN (-7125 5280);
FORCEPROP 0 LAST $SEC 1
J 0
(-7125 5425);
DISPLAY 0.680851 (-7125 5425);
PAINT MONO (-7125 5425);
DISPLAY INVISIBLE (-7125 5425);
FORCEPROP 0 LAST CDS_SEC 1
J 0
(-7125 5425);
DISPLAY 1.021277 (-7125 5425);
DISPLAY INVISIBLE (-7125 5425);
FORCEPROP 0 LASTPIN (-7275 5075) $PN 2
J 2
(-7285 5085);
DISPLAY 0.680851 (-7285 5085);
PAINT MONO (-7285 5085);
FORCEPROP 0 LASTPIN (-7275 4925) $PN 3
J 2
(-7285 4935);
DISPLAY 0.680851 (-7285 4935);
PAINT MONO (-7285 4935);
FORCEPROP 0 LASTPIN (-6725 5075) $PN 1
J 0
(-6715 5085);
DISPLAY 0.680851 (-6715 5085);
PAINT MONO (-6715 5085);
FORCEPROP 0 LASTPIN (-6725 4925) $PN 4
J 0
(-6715 4935);
DISPLAY 0.680851 (-6715 4935);
PAINT MONO (-6715 4935);
FORCEPROP 2 LAST PACK_TYPE TH
J 0
(-7125 5325);
DISPLAY 1.021277 (-7125 5325);
FORCEPROP 1 LAST MATERIAL EMPTY
J 0
(-7125 5185);
DISPLAY 0.723404 (-7125 5185);
PAINT GREEN (-7125 5185);
FORCEPROP 2 LAST VALUE TP_TDR_4P_DIP
J 0
(-7125 5375);
DISPLAY 1.021277 (-7125 5375);
FORCEPROP 1 LAST NEEDS_NO_SIZE TRUE
J 0
(-7000 5000);
DISPLAY 0.468085 (-7000 5000);
PAINT GREEN (-7000 5000);
DISPLAY INVISIBLE (-7000 5000);
FORCEPROP 2 LAST CDS_LIB pure_quanta
J 0
(-7000 5000);
DISPLAY INVISIBLE (-7000 5000);
FORCEPROP 1 LAST PATH I10
J 0
(-6900 5180);
DISPLAY 0.723404 (-6900 5180);
PAINT GREEN (-6900 5180);
DISPLAY INVISIBLE (-6900 5180);
FORCEPROP 1 LAST PART_NUMBER TP15
J 0
(-7125 5235);
DISPLAY 0.723404 (-7125 5235);
PAINT GREEN (-7125 5235);
DISPLAY INVISIBLE (-7125 5235);
FORCEADD UNIVERSAL_GND..1
(-7425 5550);
FORCEPROP 3 LASTPIN (-7425 5600) SIG_NAME T1_GND\g
J 0
(-7415 5610);
DISPLAY 0.659574 (-7415 5610);
PAINT MONO (-7415 5610);
DISPLAY INVISIBLE (-7415 5610);
FORCEPROP 1 LAST HDL_POWER T1_GND
J 1
(-7400 5475);
DISPLAY 0.872340 (-7400 5475);
PAINT GREEN (-7400 5475);
FORCEPROP 2 LAST CDS_LIB pure_quanta_power
J 0
(-7425 5550);
DISPLAY INVISIBLE (-7425 5550);
FORCEPROP 1 LAST PATH I11
J 0
(-7350 5550);
DISPLAY 0.872340 (-7350 5550);
PAINT AQUA (-7350 5550);
DISPLAY INVISIBLE (-7350 5550);
FORCEADD TP_TDR_4P_FTS..1
(-7000 5775);
FORCEPROP 1 LAST LOCATION X9002
J 0
(-7125 6055);
DISPLAY 0.723404 (-7125 6055);
PAINT GREEN (-7125 6055);
FORCEPROP 0 LAST $SEC 1
J 0
(-7125 6200);
DISPLAY 0.680851 (-7125 6200);
PAINT MONO (-7125 6200);
DISPLAY INVISIBLE (-7125 6200);
FORCEPROP 0 LAST CDS_SEC 1
J 0
(-7125 6200);
DISPLAY 1.021277 (-7125 6200);
DISPLAY INVISIBLE (-7125 6200);
FORCEPROP 0 LASTPIN (-7275 5850) $PN 2
J 2
(-7285 5860);
DISPLAY 0.680851 (-7285 5860);
PAINT MONO (-7285 5860);
FORCEPROP 0 LASTPIN (-7275 5700) $PN 3
J 2
(-7285 5710);
DISPLAY 0.680851 (-7285 5710);
PAINT MONO (-7285 5710);
FORCEPROP 0 LASTPIN (-6725 5850) $PN 1
J 0
(-6715 5860);
DISPLAY 0.680851 (-6715 5860);
PAINT MONO (-6715 5860);
FORCEPROP 0 LASTPIN (-6725 5700) $PN 4
J 0
(-6715 5710);
DISPLAY 0.680851 (-6715 5710);
PAINT MONO (-6715 5710);
FORCEPROP 2 LAST PACK_TYPE TH
J 0
(-7125 6100);
DISPLAY 1.021277 (-7125 6100);
FORCEPROP 1 LAST MATERIAL EMPTY
J 0
(-7125 5960);
DISPLAY 0.723404 (-7125 5960);
PAINT GREEN (-7125 5960);
FORCEPROP 2 LAST VALUE TP_TDR_4P_DIP
J 0
(-7125 6150);
DISPLAY 1.021277 (-7125 6150);
FORCEPROP 2 LAST CDS_LIB pure_quanta
J 0
(-7000 5775);
DISPLAY INVISIBLE (-7000 5775);
FORCEPROP 1 LAST NEEDS_NO_SIZE TRUE
J 0
(-7000 5775);
DISPLAY 0.468085 (-7000 5775);
PAINT GREEN (-7000 5775);
DISPLAY INVISIBLE (-7000 5775);
FORCEPROP 1 LAST PATH I12
J 0
(-6900 5955);
DISPLAY 0.723404 (-6900 5955);
PAINT GREEN (-6900 5955);
DISPLAY INVISIBLE (-6900 5955);
FORCEPROP 1 LAST PART_NUMBER TP15
J 0
(-7125 6010);
DISPLAY 0.723404 (-7125 6010);
PAINT GREEN (-7125 6010);
DISPLAY INVISIBLE (-7125 6010);
FORCEADD TP_TDR_4P_FTS..1
R 4
(-5675 2000);
FORCEPROP 1 LAST LOCATION X9028
J 0
(-5800 2295);
DISPLAY 0.723404 (-5800 2295);
PAINT GREEN (-5800 2295);
FORCEPROP 0 LAST $SEC 1
J 0
(-5800 2425);
DISPLAY 0.680851 (-5800 2425);
PAINT MONO (-5800 2425);
DISPLAY INVISIBLE (-5800 2425);
FORCEPROP 0 LAST CDS_SEC 1
J 0
(-5800 2425);
DISPLAY 1.021277 (-5800 2425);
DISPLAY INVISIBLE (-5800 2425);
FORCEPROP 0 LASTPIN (-5400 1925) $PN 2
J 0
(-5390 1935);
DISPLAY 0.680851 (-5390 1935);
PAINT MONO (-5390 1935);
FORCEPROP 0 LASTPIN (-5400 2075) $PN 3
J 0
(-5390 2085);
DISPLAY 0.680851 (-5390 2085);
PAINT MONO (-5390 2085);
FORCEPROP 0 LASTPIN (-5950 1925) $PN 1
J 2
(-5960 1935);
DISPLAY 0.680851 (-5960 1935);
PAINT MONO (-5960 1935);
FORCEPROP 0 LASTPIN (-5950 2075) $PN 4
J 2
(-5960 2085);
DISPLAY 0.680851 (-5960 2085);
PAINT MONO (-5960 2085);
FORCEPROP 2 LAST PACK_TYPE TH
J 0
(-5800 2250);
DISPLAY 1.021277 (-5800 2250);
FORCEPROP 1 LAST MATERIAL EMPTY
J 0
(-5800 2390);
DISPLAY 0.723404 (-5800 2390);
PAINT GREEN (-5800 2390);
FORCEPROP 2 LAST VALUE TP_TDR_4P_DIP
J 0
(-5800 2200);
DISPLAY 1.021277 (-5800 2200);
FORCEPROP 1 LAST NEEDS_NO_SIZE TRUE
R 2
J 0
(-5675 2000);
DISPLAY 0.468085 (-5675 2000);
PAINT GREEN (-5675 2000);
DISPLAY INVISIBLE (-5675 2000);
FORCEPROP 2 LAST CDS_LIB pure_quanta
R 2
J 0
(-5675 2000);
DISPLAY INVISIBLE (-5675 2000);
FORCEPROP 1 LAST PATH I13
R 2
J 0
(-5775 1820);
DISPLAY 0.723404 (-5775 1820);
PAINT GREEN (-5775 1820);
DISPLAY INVISIBLE (-5775 1820);
FORCEPROP 1 LAST PART_NUMBER TP15
J 0
(-5800 2340);
DISPLAY 0.723404 (-5800 2340);
PAINT GREEN (-5800 2340);
DISPLAY INVISIBLE (-5800 2340);
FORCEADD UNIVERSAL_GND..1
(-5275 1775);
FORCEPROP 3 LASTPIN (-5275 1825) SIG_NAME T1_GND\g
J 0
(-5265 1835);
DISPLAY 0.659574 (-5265 1835);
PAINT MONO (-5265 1835);
DISPLAY INVISIBLE (-5265 1835);
FORCEPROP 1 LAST HDL_POWER T1_GND
J 1
(-5250 1700);
DISPLAY 0.872340 (-5250 1700);
PAINT GREEN (-5250 1700);
FORCEPROP 2 LAST CDS_LIB pure_quanta_power
J 0
(-5275 1775);
DISPLAY INVISIBLE (-5275 1775);
FORCEPROP 1 LAST PATH I14
J 0
(-5200 1775);
DISPLAY 0.872340 (-5200 1775);
PAINT AQUA (-5200 1775);
DISPLAY INVISIBLE (-5200 1775);
FORCEADD TP_TDR_4P_FTS..1
R 4
(-5675 2775);
FORCEPROP 1 LAST LOCATION X9027
J 0
(-5800 3070);
DISPLAY 0.723404 (-5800 3070);
PAINT GREEN (-5800 3070);
FORCEPROP 0 LAST $SEC 1
J 0
(-5800 3200);
DISPLAY 0.680851 (-5800 3200);
PAINT MONO (-5800 3200);
DISPLAY INVISIBLE (-5800 3200);
FORCEPROP 0 LAST CDS_SEC 1
J 0
(-5800 3200);
DISPLAY 1.021277 (-5800 3200);
DISPLAY INVISIBLE (-5800 3200);
FORCEPROP 0 LASTPIN (-5400 2700) $PN 2
J 0
(-5390 2710);
DISPLAY 0.680851 (-5390 2710);
PAINT MONO (-5390 2710);
FORCEPROP 0 LASTPIN (-5400 2850) $PN 3
J 0
(-5390 2860);
DISPLAY 0.680851 (-5390 2860);
PAINT MONO (-5390 2860);
FORCEPROP 0 LASTPIN (-5950 2700) $PN 1
J 2
(-5960 2710);
DISPLAY 0.680851 (-5960 2710);
PAINT MONO (-5960 2710);
FORCEPROP 0 LASTPIN (-5950 2850) $PN 4
J 2
(-5960 2860);
DISPLAY 0.680851 (-5960 2860);
PAINT MONO (-5960 2860);
FORCEPROP 2 LAST PACK_TYPE TH
J 0
(-5800 3025);
DISPLAY 1.021277 (-5800 3025);
FORCEPROP 2 LAST VALUE TP_TDR_4P_DIP
J 0
(-5800 2975);
DISPLAY 1.021277 (-5800 2975);
FORCEPROP 1 LAST MATERIAL EMPTY
J 0
(-5800 3165);
DISPLAY 0.723404 (-5800 3165);
PAINT GREEN (-5800 3165);
FORCEPROP 1 LAST NEEDS_NO_SIZE TRUE
R 2
J 0
(-5675 2775);
DISPLAY 0.468085 (-5675 2775);
PAINT GREEN (-5675 2775);
DISPLAY INVISIBLE (-5675 2775);
FORCEPROP 2 LAST CDS_LIB pure_quanta
R 2
J 0
(-5675 2775);
DISPLAY INVISIBLE (-5675 2775);
FORCEPROP 1 LAST PATH I15
R 2
J 0
(-5775 2595);
DISPLAY 0.723404 (-5775 2595);
PAINT GREEN (-5775 2595);
DISPLAY INVISIBLE (-5775 2595);
FORCEPROP 1 LAST PART_NUMBER TP15
J 0
(-5800 3115);
DISPLAY 0.723404 (-5800 3115);
PAINT GREEN (-5800 3115);
DISPLAY INVISIBLE (-5800 3115);
FORCEADD TP_TDR_4P_FTS..1
R 4
(-5675 4225);
FORCEPROP 1 LAST LOCATION X9010
J 0
(-5800 4520);
DISPLAY 0.723404 (-5800 4520);
PAINT GREEN (-5800 4520);
FORCEPROP 0 LAST $SEC 1
J 0
(-5800 4650);
DISPLAY 0.680851 (-5800 4650);
PAINT MONO (-5800 4650);
DISPLAY INVISIBLE (-5800 4650);
FORCEPROP 0 LAST CDS_SEC 1
J 0
(-5800 4650);
DISPLAY 1.021277 (-5800 4650);
DISPLAY INVISIBLE (-5800 4650);
FORCEPROP 0 LASTPIN (-5400 4150) $PN 2
J 0
(-5390 4160);
DISPLAY 0.680851 (-5390 4160);
PAINT MONO (-5390 4160);
FORCEPROP 0 LASTPIN (-5400 4300) $PN 3
J 0
(-5390 4310);
DISPLAY 0.680851 (-5390 4310);
PAINT MONO (-5390 4310);
FORCEPROP 0 LASTPIN (-5950 4150) $PN 1
J 2
(-5960 4160);
DISPLAY 0.680851 (-5960 4160);
PAINT MONO (-5960 4160);
FORCEPROP 0 LASTPIN (-5950 4300) $PN 4
J 2
(-5960 4310);
DISPLAY 0.680851 (-5960 4310);
PAINT MONO (-5960 4310);
FORCEPROP 2 LAST PACK_TYPE TH
J 0
(-5800 4475);
DISPLAY 1.021277 (-5800 4475);
FORCEPROP 2 LAST VALUE TP_TDR_4P_DIP
J 0
(-5800 4425);
DISPLAY 1.021277 (-5800 4425);
FORCEPROP 1 LAST MATERIAL EMPTY
J 0
(-5800 4615);
DISPLAY 0.723404 (-5800 4615);
PAINT GREEN (-5800 4615);
FORCEPROP 1 LAST NEEDS_NO_SIZE TRUE
R 2
J 0
(-5675 4225);
DISPLAY 0.468085 (-5675 4225);
PAINT GREEN (-5675 4225);
DISPLAY INVISIBLE (-5675 4225);
FORCEPROP 2 LAST CDS_LIB pure_quanta
R 2
J 0
(-5675 4225);
DISPLAY INVISIBLE (-5675 4225);
FORCEPROP 1 LAST PATH I16
R 2
J 0
(-5775 4045);
DISPLAY 0.723404 (-5775 4045);
PAINT GREEN (-5775 4045);
DISPLAY INVISIBLE (-5775 4045);
FORCEPROP 1 LAST PART_NUMBER TP15
J 0
(-5800 4565);
DISPLAY 0.723404 (-5800 4565);
PAINT GREEN (-5800 4565);
DISPLAY INVISIBLE (-5800 4565);
FORCEADD TP_TDR_4P_FTS..1
R 4
(-5675 3450);
FORCEPROP 1 LAST LOCATION X9011
J 0
(-5800 3745);
DISPLAY 0.723404 (-5800 3745);
PAINT GREEN (-5800 3745);
FORCEPROP 0 LAST $SEC 1
J 0
(-5800 3875);
DISPLAY 0.680851 (-5800 3875);
PAINT MONO (-5800 3875);
DISPLAY INVISIBLE (-5800 3875);
FORCEPROP 0 LAST CDS_SEC 1
J 0
(-5800 3875);
DISPLAY 1.021277 (-5800 3875);
DISPLAY INVISIBLE (-5800 3875);
FORCEPROP 0 LASTPIN (-5400 3375) $PN 2
J 0
(-5390 3385);
DISPLAY 0.680851 (-5390 3385);
PAINT MONO (-5390 3385);
FORCEPROP 0 LASTPIN (-5400 3525) $PN 3
J 0
(-5390 3535);
DISPLAY 0.680851 (-5390 3535);
PAINT MONO (-5390 3535);
FORCEPROP 0 LASTPIN (-5950 3375) $PN 1
J 2
(-5960 3385);
DISPLAY 0.680851 (-5960 3385);
PAINT MONO (-5960 3385);
FORCEPROP 0 LASTPIN (-5950 3525) $PN 4
J 2
(-5960 3535);
DISPLAY 0.680851 (-5960 3535);
PAINT MONO (-5960 3535);
FORCEPROP 2 LAST PACK_TYPE TH
J 0
(-5800 3700);
DISPLAY 1.021277 (-5800 3700);
FORCEPROP 1 LAST MATERIAL EMPTY
J 0
(-5800 3840);
DISPLAY 0.723404 (-5800 3840);
PAINT GREEN (-5800 3840);
FORCEPROP 2 LAST VALUE TP_TDR_4P_DIP
J 0
(-5800 3650);
DISPLAY 1.021277 (-5800 3650);
FORCEPROP 1 LAST NEEDS_NO_SIZE TRUE
R 2
J 0
(-5675 3450);
DISPLAY 0.468085 (-5675 3450);
PAINT GREEN (-5675 3450);
DISPLAY INVISIBLE (-5675 3450);
FORCEPROP 2 LAST CDS_LIB pure_quanta
R 2
J 0
(-5675 3450);
DISPLAY INVISIBLE (-5675 3450);
FORCEPROP 1 LAST PATH I17
R 2
J 0
(-5775 3270);
DISPLAY 0.723404 (-5775 3270);
PAINT GREEN (-5775 3270);
DISPLAY INVISIBLE (-5775 3270);
FORCEPROP 1 LAST PART_NUMBER TP15
J 0
(-5800 3790);
DISPLAY 0.723404 (-5800 3790);
PAINT GREEN (-5800 3790);
DISPLAY INVISIBLE (-5800 3790);
FORCEADD UNIVERSAL_GND..1
(-5275 2550);
FORCEPROP 3 LASTPIN (-5275 2600) SIG_NAME T1_GND\g
J 0
(-5265 2610);
DISPLAY 0.659574 (-5265 2610);
PAINT MONO (-5265 2610);
DISPLAY INVISIBLE (-5265 2610);
FORCEPROP 1 LAST HDL_POWER T1_GND
J 1
(-5250 2475);
DISPLAY 0.872340 (-5250 2475);
PAINT GREEN (-5250 2475);
FORCEPROP 2 LAST CDS_LIB pure_quanta_power
J 0
(-5275 2550);
DISPLAY INVISIBLE (-5275 2550);
FORCEPROP 1 LAST PATH I18
J 0
(-5200 2550);
DISPLAY 0.872340 (-5200 2550);
PAINT AQUA (-5200 2550);
DISPLAY INVISIBLE (-5200 2550);
FORCEADD UNIVERSAL_GND..1
(-5275 4000);
FORCEPROP 3 LASTPIN (-5275 4050) SIG_NAME T1_GND\g
J 0
(-5265 4060);
DISPLAY 0.659574 (-5265 4060);
PAINT MONO (-5265 4060);
DISPLAY INVISIBLE (-5265 4060);
FORCEPROP 1 LAST HDL_POWER T1_GND
J 1
(-5250 3925);
DISPLAY 0.872340 (-5250 3925);
PAINT GREEN (-5250 3925);
FORCEPROP 2 LAST CDS_LIB pure_quanta_power
J 0
(-5275 4000);
DISPLAY INVISIBLE (-5275 4000);
FORCEPROP 1 LAST PATH I19
J 0
(-5200 4000);
DISPLAY 0.872340 (-5200 4000);
PAINT AQUA (-5200 4000);
DISPLAY INVISIBLE (-5200 4000);
FORCEADD TP_TDR_4P_FTS..1
(-7000 2000);
FORCEPROP 1 LAST LOCATION X9026
J 0
(-7125 2280);
DISPLAY 0.723404 (-7125 2280);
PAINT GREEN (-7125 2280);
FORCEPROP 0 LAST $SEC 1
J 0
(-7125 2425);
DISPLAY 0.680851 (-7125 2425);
PAINT MONO (-7125 2425);
DISPLAY INVISIBLE (-7125 2425);
FORCEPROP 0 LAST CDS_SEC 1
J 0
(-7125 2425);
DISPLAY 1.021277 (-7125 2425);
DISPLAY INVISIBLE (-7125 2425);
FORCEPROP 0 LASTPIN (-7275 2075) $PN 2
J 2
(-7285 2085);
DISPLAY 0.680851 (-7285 2085);
PAINT MONO (-7285 2085);
FORCEPROP 0 LASTPIN (-7275 1925) $PN 3
J 2
(-7285 1935);
DISPLAY 0.680851 (-7285 1935);
PAINT MONO (-7285 1935);
FORCEPROP 0 LASTPIN (-6725 2075) $PN 1
J 0
(-6715 2085);
DISPLAY 0.680851 (-6715 2085);
PAINT MONO (-6715 2085);
FORCEPROP 0 LASTPIN (-6725 1925) $PN 4
J 0
(-6715 1935);
DISPLAY 0.680851 (-6715 1935);
PAINT MONO (-6715 1935);
FORCEPROP 1 LAST MATERIAL EMPTY
J 0
(-7125 2185);
DISPLAY 0.723404 (-7125 2185);
PAINT GREEN (-7125 2185);
FORCEPROP 2 LAST PACK_TYPE TH
J 0
(-7125 2325);
DISPLAY 1.021277 (-7125 2325);
FORCEPROP 2 LAST VALUE TP_TDR_4P_DIP
J 0
(-7125 2375);
DISPLAY 1.021277 (-7125 2375);
FORCEPROP 1 LAST NEEDS_NO_SIZE TRUE
J 0
(-7000 2000);
DISPLAY 0.468085 (-7000 2000);
PAINT GREEN (-7000 2000);
DISPLAY INVISIBLE (-7000 2000);
FORCEPROP 2 LAST CDS_LIB pure_quanta
J 0
(-7000 2000);
DISPLAY INVISIBLE (-7000 2000);
FORCEPROP 1 LAST PATH I2
J 0
(-6900 2180);
DISPLAY 0.723404 (-6900 2180);
PAINT GREEN (-6900 2180);
DISPLAY INVISIBLE (-6900 2180);
FORCEPROP 1 LAST PART_NUMBER TP15
J 0
(-7125 2235);
DISPLAY 0.723404 (-7125 2235);
PAINT GREEN (-7125 2235);
DISPLAY INVISIBLE (-7125 2235);
FORCEADD UNIVERSAL_GND..1
(-5275 3225);
FORCEPROP 3 LASTPIN (-5275 3275) SIG_NAME T1_GND\g
J 0
(-5265 3285);
DISPLAY 0.659574 (-5265 3285);
PAINT MONO (-5265 3285);
DISPLAY INVISIBLE (-5265 3285);
FORCEPROP 1 LAST HDL_POWER T1_GND
J 1
(-5250 3150);
DISPLAY 0.872340 (-5250 3150);
PAINT GREEN (-5250 3150);
FORCEPROP 2 LAST CDS_LIB pure_quanta_power
J 0
(-5275 3225);
DISPLAY INVISIBLE (-5275 3225);
FORCEPROP 1 LAST PATH I20
J 0
(-5200 3225);
DISPLAY 0.872340 (-5200 3225);
PAINT AQUA (-5200 3225);
DISPLAY INVISIBLE (-5200 3225);
FORCEADD UNIVERSAL_GND..1
(-7425 2550);
FORCEPROP 3 LASTPIN (-7425 2600) SIG_NAME T1_GND\g
J 0
(-7415 2610);
DISPLAY 0.659574 (-7415 2610);
PAINT MONO (-7415 2610);
DISPLAY INVISIBLE (-7415 2610);
FORCEPROP 1 LAST HDL_POWER T1_GND
J 1
(-7400 2475);
DISPLAY 0.872340 (-7400 2475);
PAINT GREEN (-7400 2475);
FORCEPROP 2 LAST CDS_LIB pure_quanta_power
J 0
(-7425 2550);
DISPLAY INVISIBLE (-7425 2550);
FORCEPROP 1 LAST PATH I3
J 0
(-7350 2550);
DISPLAY 0.872340 (-7350 2550);
PAINT AQUA (-7350 2550);
DISPLAY INVISIBLE (-7350 2550);
FORCEADD TP_TDR_4P_FTS..1
R 4
(-5675 5000);
FORCEPROP 1 LAST LOCATION X9009
J 0
(-5800 5295);
DISPLAY 0.723404 (-5800 5295);
PAINT GREEN (-5800 5295);
FORCEPROP 0 LAST $SEC 1
J 0
(-5800 5425);
DISPLAY 0.680851 (-5800 5425);
PAINT MONO (-5800 5425);
DISPLAY INVISIBLE (-5800 5425);
FORCEPROP 0 LAST CDS_SEC 1
J 0
(-5800 5425);
DISPLAY 1.021277 (-5800 5425);
DISPLAY INVISIBLE (-5800 5425);
FORCEPROP 0 LASTPIN (-5400 4925) $PN 2
J 0
(-5390 4935);
DISPLAY 0.680851 (-5390 4935);
PAINT MONO (-5390 4935);
FORCEPROP 0 LASTPIN (-5400 5075) $PN 3
J 0
(-5390 5085);
DISPLAY 0.680851 (-5390 5085);
PAINT MONO (-5390 5085);
FORCEPROP 0 LASTPIN (-5950 4925) $PN 1
J 2
(-5960 4935);
DISPLAY 0.680851 (-5960 4935);
PAINT MONO (-5960 4935);
FORCEPROP 0 LASTPIN (-5950 5075) $PN 4
J 2
(-5960 5085);
DISPLAY 0.680851 (-5960 5085);
PAINT MONO (-5960 5085);
FORCEPROP 2 LAST PACK_TYPE TH
J 0
(-5800 5250);
DISPLAY 1.021277 (-5800 5250);
FORCEPROP 1 LAST MATERIAL EMPTY
J 0
(-5800 5390);
DISPLAY 0.723404 (-5800 5390);
PAINT GREEN (-5800 5390);
FORCEPROP 2 LAST VALUE TP_TDR_4P_DIP
J 0
(-5800 5200);
DISPLAY 1.021277 (-5800 5200);
FORCEPROP 1 LAST NEEDS_NO_SIZE TRUE
R 2
J 0
(-5675 5000);
DISPLAY 0.468085 (-5675 5000);
PAINT GREEN (-5675 5000);
DISPLAY INVISIBLE (-5675 5000);
FORCEPROP 2 LAST CDS_LIB pure_quanta
R 2
J 0
(-5675 5000);
DISPLAY INVISIBLE (-5675 5000);
FORCEPROP 1 LAST PATH I37
R 2
J 0
(-5775 4820);
DISPLAY 0.723404 (-5775 4820);
PAINT GREEN (-5775 4820);
DISPLAY INVISIBLE (-5775 4820);
FORCEPROP 1 LAST PART_NUMBER TP15
J 0
(-5800 5340);
DISPLAY 0.723404 (-5800 5340);
PAINT GREEN (-5800 5340);
DISPLAY INVISIBLE (-5800 5340);
FORCEADD TP_TDR_4P_FTS..1
R 4
(-5675 5775);
FORCEPROP 1 LAST LOCATION X9008
J 0
(-5800 6070);
DISPLAY 0.723404 (-5800 6070);
PAINT GREEN (-5800 6070);
FORCEPROP 0 LAST $SEC 1
J 0
(-5800 6200);
DISPLAY 0.680851 (-5800 6200);
PAINT MONO (-5800 6200);
DISPLAY INVISIBLE (-5800 6200);
FORCEPROP 0 LAST CDS_SEC 1
J 0
(-5800 6200);
DISPLAY 1.021277 (-5800 6200);
DISPLAY INVISIBLE (-5800 6200);
FORCEPROP 0 LASTPIN (-5400 5700) $PN 2
J 0
(-5390 5710);
DISPLAY 0.680851 (-5390 5710);
PAINT MONO (-5390 5710);
FORCEPROP 0 LASTPIN (-5400 5850) $PN 3
J 0
(-5390 5860);
DISPLAY 0.680851 (-5390 5860);
PAINT MONO (-5390 5860);
FORCEPROP 0 LASTPIN (-5950 5700) $PN 1
J 2
(-5960 5710);
DISPLAY 0.680851 (-5960 5710);
PAINT MONO (-5960 5710);
FORCEPROP 0 LASTPIN (-5950 5850) $PN 4
J 2
(-5960 5860);
DISPLAY 0.680851 (-5960 5860);
PAINT MONO (-5960 5860);
FORCEPROP 2 LAST PACK_TYPE TH
J 0
(-5800 6025);
DISPLAY 1.021277 (-5800 6025);
FORCEPROP 1 LAST MATERIAL EMPTY
J 0
(-5800 6165);
DISPLAY 0.723404 (-5800 6165);
PAINT GREEN (-5800 6165);
FORCEPROP 2 LAST VALUE TP_TDR_4P_DIP
J 0
(-5800 5975);
DISPLAY 1.021277 (-5800 5975);
FORCEPROP 2 LAST CDS_LIB pure_quanta
R 2
J 0
(-5675 5775);
DISPLAY INVISIBLE (-5675 5775);
FORCEPROP 1 LAST NEEDS_NO_SIZE TRUE
R 2
J 0
(-5675 5775);
DISPLAY 0.468085 (-5675 5775);
PAINT GREEN (-5675 5775);
DISPLAY INVISIBLE (-5675 5775);
FORCEPROP 1 LAST PATH I38
R 2
J 0
(-5775 5595);
DISPLAY 0.723404 (-5775 5595);
PAINT GREEN (-5775 5595);
DISPLAY INVISIBLE (-5775 5595);
FORCEPROP 1 LAST PART_NUMBER TP15
J 0
(-5800 6115);
DISPLAY 0.723404 (-5800 6115);
PAINT GREEN (-5800 6115);
DISPLAY INVISIBLE (-5800 6115);
FORCEADD UNIVERSAL_GND..1
(-5275 4775);
FORCEPROP 3 LASTPIN (-5275 4825) SIG_NAME T1_GND\g
J 0
(-5265 4835);
DISPLAY 0.659574 (-5265 4835);
PAINT MONO (-5265 4835);
DISPLAY INVISIBLE (-5265 4835);
FORCEPROP 1 LAST HDL_POWER T1_GND
J 1
(-5250 4700);
DISPLAY 0.872340 (-5250 4700);
PAINT GREEN (-5250 4700);
FORCEPROP 2 LAST CDS_LIB pure_quanta_power
J 0
(-5275 4775);
DISPLAY INVISIBLE (-5275 4775);
FORCEPROP 1 LAST PATH I39
J 0
(-5200 4775);
DISPLAY 0.872340 (-5200 4775);
PAINT AQUA (-5200 4775);
DISPLAY INVISIBLE (-5200 4775);
FORCEADD TP_TDR_4P_FTS..1
(-7000 2775);
FORCEPROP 1 LAST LOCATION X9025
J 0
(-7125 3055);
DISPLAY 0.723404 (-7125 3055);
PAINT GREEN (-7125 3055);
FORCEPROP 0 LAST $SEC 1
J 0
(-7125 3200);
DISPLAY 0.680851 (-7125 3200);
PAINT MONO (-7125 3200);
DISPLAY INVISIBLE (-7125 3200);
FORCEPROP 0 LAST CDS_SEC 1
J 0
(-7125 3200);
DISPLAY 1.021277 (-7125 3200);
DISPLAY INVISIBLE (-7125 3200);
FORCEPROP 0 LASTPIN (-7275 2850) $PN 2
J 2
(-7285 2860);
DISPLAY 0.680851 (-7285 2860);
PAINT MONO (-7285 2860);
FORCEPROP 0 LASTPIN (-7275 2700) $PN 3
J 2
(-7285 2710);
DISPLAY 0.680851 (-7285 2710);
PAINT MONO (-7285 2710);
FORCEPROP 0 LASTPIN (-6725 2850) $PN 1
J 0
(-6715 2860);
DISPLAY 0.680851 (-6715 2860);
PAINT MONO (-6715 2860);
FORCEPROP 0 LASTPIN (-6725 2700) $PN 4
J 0
(-6715 2710);
DISPLAY 0.680851 (-6715 2710);
PAINT MONO (-6715 2710);
FORCEPROP 1 LAST MATERIAL EMPTY
J 0
(-7125 2960);
DISPLAY 0.723404 (-7125 2960);
PAINT GREEN (-7125 2960);
FORCEPROP 2 LAST PACK_TYPE TH
J 0
(-7125 3100);
DISPLAY 1.021277 (-7125 3100);
FORCEPROP 2 LAST VALUE TP_TDR_4P_DIP
J 0
(-7125 3150);
DISPLAY 1.021277 (-7125 3150);
FORCEPROP 1 LAST NEEDS_NO_SIZE TRUE
J 0
(-7000 2775);
DISPLAY 0.468085 (-7000 2775);
PAINT GREEN (-7000 2775);
DISPLAY INVISIBLE (-7000 2775);
FORCEPROP 2 LAST CDS_LIB pure_quanta
J 0
(-7000 2775);
DISPLAY INVISIBLE (-7000 2775);
FORCEPROP 1 LAST PATH I4
J 0
(-6900 2955);
DISPLAY 0.723404 (-6900 2955);
PAINT GREEN (-6900 2955);
DISPLAY INVISIBLE (-6900 2955);
FORCEPROP 1 LAST PART_NUMBER TP15
J 0
(-7125 3010);
DISPLAY 0.723404 (-7125 3010);
PAINT GREEN (-7125 3010);
DISPLAY INVISIBLE (-7125 3010);
FORCEADD UNIVERSAL_GND..1
(-5275 5550);
FORCEPROP 3 LASTPIN (-5275 5600) SIG_NAME T1_GND\g
J 0
(-5265 5610);
DISPLAY 0.659574 (-5265 5610);
PAINT MONO (-5265 5610);
DISPLAY INVISIBLE (-5265 5610);
FORCEPROP 1 LAST HDL_POWER T1_GND
J 1
(-5250 5475);
DISPLAY 0.872340 (-5250 5475);
PAINT GREEN (-5250 5475);
FORCEPROP 2 LAST CDS_LIB pure_quanta_power
J 0
(-5275 5550);
DISPLAY INVISIBLE (-5275 5550);
FORCEPROP 1 LAST PATH I40
J 0
(-5200 5550);
DISPLAY 0.872340 (-5200 5550);
PAINT AQUA (-5200 5550);
DISPLAY INVISIBLE (-5200 5550);
FORCEADD UNIVERSAL_GND..1
(-7425 3225);
FORCEPROP 3 LASTPIN (-7425 3275) SIG_NAME T1_GND\g
J 0
(-7415 3285);
DISPLAY 0.659574 (-7415 3285);
PAINT MONO (-7415 3285);
DISPLAY INVISIBLE (-7415 3285);
FORCEPROP 1 LAST HDL_POWER T1_GND
J 1
(-7400 3150);
DISPLAY 0.872340 (-7400 3150);
PAINT GREEN (-7400 3150);
FORCEPROP 2 LAST CDS_LIB pure_quanta_power
J 0
(-7425 3225);
DISPLAY INVISIBLE (-7425 3225);
FORCEPROP 1 LAST PATH I5
J 0
(-7350 3225);
DISPLAY 0.872340 (-7350 3225);
PAINT AQUA (-7350 3225);
DISPLAY INVISIBLE (-7350 3225);
FORCEADD UNIVERSAL_GND..1
(-7425 4000);
FORCEPROP 3 LASTPIN (-7425 4050) SIG_NAME T1_GND\g
J 0
(-7415 4060);
DISPLAY 0.659574 (-7415 4060);
PAINT MONO (-7415 4060);
DISPLAY INVISIBLE (-7415 4060);
FORCEPROP 1 LAST HDL_POWER T1_GND
J 1
(-7400 3925);
DISPLAY 0.872340 (-7400 3925);
PAINT GREEN (-7400 3925);
FORCEPROP 2 LAST CDS_LIB pure_quanta_power
J 0
(-7425 4000);
DISPLAY INVISIBLE (-7425 4000);
FORCEPROP 1 LAST PATH I6
J 0
(-7350 4000);
DISPLAY 0.872340 (-7350 4000);
PAINT AQUA (-7350 4000);
DISPLAY INVISIBLE (-7350 4000);
FORCEADD TP_TDR_4P_FTS..1
(-7000 3450);
FORCEPROP 1 LAST LOCATION X9005
J 0
(-7125 3730);
DISPLAY 0.723404 (-7125 3730);
PAINT GREEN (-7125 3730);
FORCEPROP 0 LAST $SEC 1
J 0
(-7125 3875);
DISPLAY 0.680851 (-7125 3875);
PAINT MONO (-7125 3875);
DISPLAY INVISIBLE (-7125 3875);
FORCEPROP 0 LAST CDS_SEC 1
J 0
(-7125 3875);
DISPLAY 1.021277 (-7125 3875);
DISPLAY INVISIBLE (-7125 3875);
FORCEPROP 0 LASTPIN (-7275 3525) $PN 2
J 2
(-7285 3535);
DISPLAY 0.680851 (-7285 3535);
PAINT MONO (-7285 3535);
FORCEPROP 0 LASTPIN (-7275 3375) $PN 3
J 2
(-7285 3385);
DISPLAY 0.680851 (-7285 3385);
PAINT MONO (-7285 3385);
FORCEPROP 0 LASTPIN (-6725 3525) $PN 1
J 0
(-6715 3535);
DISPLAY 0.680851 (-6715 3535);
PAINT MONO (-6715 3535);
FORCEPROP 0 LASTPIN (-6725 3375) $PN 4
J 0
(-6715 3385);
DISPLAY 0.680851 (-6715 3385);
PAINT MONO (-6715 3385);
FORCEPROP 1 LAST MATERIAL EMPTY
J 0
(-7125 3635);
DISPLAY 0.723404 (-7125 3635);
PAINT GREEN (-7125 3635);
FORCEPROP 2 LAST PACK_TYPE TH
J 0
(-7125 3775);
DISPLAY 1.021277 (-7125 3775);
FORCEPROP 2 LAST VALUE TP_TDR_4P_DIP
J 0
(-7125 3825);
DISPLAY 1.021277 (-7125 3825);
FORCEPROP 1 LAST NEEDS_NO_SIZE TRUE
J 0
(-7000 3450);
DISPLAY 0.468085 (-7000 3450);
PAINT GREEN (-7000 3450);
DISPLAY INVISIBLE (-7000 3450);
FORCEPROP 2 LAST CDS_LIB pure_quanta
J 0
(-7000 3450);
DISPLAY INVISIBLE (-7000 3450);
FORCEPROP 1 LAST PATH I7
J 0
(-6900 3630);
DISPLAY 0.723404 (-6900 3630);
PAINT GREEN (-6900 3630);
DISPLAY INVISIBLE (-6900 3630);
FORCEPROP 1 LAST PART_NUMBER TP15
J 0
(-7125 3685);
DISPLAY 0.723404 (-7125 3685);
PAINT GREEN (-7125 3685);
DISPLAY INVISIBLE (-7125 3685);
FORCEADD TP_TDR_4P_FTS..1
(-7000 4225);
FORCEPROP 1 LAST LOCATION X9004
J 0
(-7125 4505);
DISPLAY 0.723404 (-7125 4505);
PAINT GREEN (-7125 4505);
FORCEPROP 0 LAST $SEC 1
J 0
(-7125 4650);
DISPLAY 0.680851 (-7125 4650);
PAINT MONO (-7125 4650);
DISPLAY INVISIBLE (-7125 4650);
FORCEPROP 0 LAST CDS_SEC 1
J 0
(-7125 4650);
DISPLAY 1.021277 (-7125 4650);
DISPLAY INVISIBLE (-7125 4650);
FORCEPROP 0 LASTPIN (-7275 4300) $PN 2
J 2
(-7285 4310);
DISPLAY 0.680851 (-7285 4310);
PAINT MONO (-7285 4310);
FORCEPROP 0 LASTPIN (-7275 4150) $PN 3
J 2
(-7285 4160);
DISPLAY 0.680851 (-7285 4160);
PAINT MONO (-7285 4160);
FORCEPROP 0 LASTPIN (-6725 4300) $PN 1
J 0
(-6715 4310);
DISPLAY 0.680851 (-6715 4310);
PAINT MONO (-6715 4310);
FORCEPROP 0 LASTPIN (-6725 4150) $PN 4
J 0
(-6715 4160);
DISPLAY 0.680851 (-6715 4160);
PAINT MONO (-6715 4160);
FORCEPROP 1 LAST MATERIAL EMPTY
J 0
(-7125 4410);
DISPLAY 0.723404 (-7125 4410);
PAINT GREEN (-7125 4410);
FORCEPROP 2 LAST PACK_TYPE TH
J 0
(-7125 4550);
DISPLAY 1.021277 (-7125 4550);
FORCEPROP 2 LAST VALUE TP_TDR_4P_DIP
J 0
(-7125 4600);
DISPLAY 1.021277 (-7125 4600);
FORCEPROP 1 LAST NEEDS_NO_SIZE TRUE
J 0
(-7000 4225);
DISPLAY 0.468085 (-7000 4225);
PAINT GREEN (-7000 4225);
DISPLAY INVISIBLE (-7000 4225);
FORCEPROP 2 LAST CDS_LIB pure_quanta
J 0
(-7000 4225);
DISPLAY INVISIBLE (-7000 4225);
FORCEPROP 1 LAST PATH I8
J 0
(-6900 4405);
DISPLAY 0.723404 (-6900 4405);
PAINT GREEN (-6900 4405);
DISPLAY INVISIBLE (-6900 4405);
FORCEPROP 1 LAST PART_NUMBER TP15
J 0
(-7125 4460);
DISPLAY 0.723404 (-7125 4460);
PAINT GREEN (-7125 4460);
DISPLAY INVISIBLE (-7125 4460);
FORCEADD UNIVERSAL_GND..1
(-7425 4775);
FORCEPROP 3 LASTPIN (-7425 4825) SIG_NAME T1_GND\g
J 0
(-7415 4835);
DISPLAY 0.659574 (-7415 4835);
PAINT MONO (-7415 4835);
DISPLAY INVISIBLE (-7415 4835);
FORCEPROP 1 LAST HDL_POWER T1_GND
J 1
(-7400 4700);
DISPLAY 0.872340 (-7400 4700);
PAINT GREEN (-7400 4700);
FORCEPROP 2 LAST CDS_LIB pure_quanta_power
J 0
(-7425 4775);
DISPLAY INVISIBLE (-7425 4775);
FORCEPROP 1 LAST PATH I9
J 0
(-7350 4775);
DISPLAY 0.872340 (-7350 4775);
PAINT AQUA (-7350 4775);
DISPLAY INVISIBLE (-7350 4775);
FORCEADD QUANTA_TITLE_BLOCK_C..1
(-1500 575);
FORCEPROP 0 LAST CDS_CON_LAST_MODIFIED Thu Sep 14 16:12:46 2023
J 0
(-3385 590);
DISPLAY INVISIBLE (-3385 590);
FORCEPROP 1 LAST CUSTOM_TXT_CDS <CON_LAST_MODIFIED>
J 0
(-3385 590);
DISPLAY 0.978723 (-3385 590);
FORCEPROP 2 LAST CUSTOM_TXT_CDS <XR_PAGE_TITLE>
J 0
(-9390 5825);
DISPLAY 0.638298 (-9390 5825);
PAINT PINK (-9390 5825);
DISPLAY INVISIBLE (-9390 5825);
FORCEPROP 1 LAST CUSTOM_TXT_CDS <NAME_2>
J 0
(-4675 625);
FORCEPROP 1 LAST CUSTOM_TXT_CDS <NAME_1>
J 0
(-4675 750);
FORCEPROP 1 LAST CUSTOM_TXT_CDS <Q_NUMBER>
J 0
(-2903 678);
DISPLAY 1.212766 (-2903 678);
FORCEPROP 1 LAST CUSTOM_TXT_CDS <Q_PROJ>
J 0
(-3882 677);
DISPLAY 1.212766 (-3882 677);
FORCEPROP 1 LAST CUSTOM_TXT_CDS <Q_REV>
J 0
(-1684 678);
DISPLAY 1.212766 (-1684 678);
FORCEPROP 1 LAST CUSTOM_TXT_CDS <CON_PAGE_NUM> OF <CON_TOTAL_PAGES>
J 0
(-1946 593);
DISPLAY 0.978723 (-1946 593);
FORCEPROP 1 LAST Q_TITLE TDR_2
J 0
(-10866 601);
DISPLAY 2.446809 (-10866 601);
PAINT GREEN (-10866 601);
FORCEPROP 2 LAST PAGE_BORDER TRUE
J 0
(-9390 5825);
DISPLAY 0.638298 (-9390 5825);
PAINT PINK (-9390 5825);
DISPLAY INVISIBLE (-9390 5825);
FORCEPROP 1 LAST CDS_LMAN_SYM_OUTLINE -9475,6775,100,-125
J 0
(-1500 575);
DISPLAY 0.468085 (-1500 575);
PAINT GREEN (-1500 575);
DISPLAY INVISIBLE (-1500 575);
FORCEPROP 2 LAST CDS_LIB pure_quanta
J 0
(-1500 575);
DISPLAY INVISIBLE (-1500 575);
FORCEPROP 2 LAST CDS_XR_PAGE_TITLE CR-262 : @T6G_MB_LIB.T6G(SCH_1):PAGE262
J 0
(-9390 5825);
DISPLAY 0.638298 (-9390 5825);
PAINT PINK (-9390 5825);
DISPLAY INVISIBLE (-9390 5825);
FORCEPROP 1 LAST Q_DEPT BU9
J 1
(-5263 624);
DISPLAY 1.957447 (-5263 624);
PAINT GREEN (-5263 624);
DISPLAY INVISIBLE (-5263 624);
FORCEPROP 1 LAST COMMENT_BODY TRUE
J 0
(-1488 562);
DISPLAY 0.978723 (-1488 562);
PAINT GREEN (-1488 562);
DISPLAY INVISIBLE (-1488 562);
WIRE 16 -1 (-5275 5700)(-5275 5850);
WIRE 16 -1 (-5400 5700)(-5275 5700);
WIRE 16 -1 (-5275 5600)(-5275 5700);
WIRE 16 -1 (-5275 5850)(-5400 5850);
WIRE 16 -1 (-5275 4925)(-5275 5075);
WIRE 16 -1 (-5275 4825)(-5275 4925);
WIRE 16 -1 (-5400 4925)(-5275 4925);
WIRE 16 -1 (-5275 5075)(-5400 5075);
WIRE 16 -1 (-5275 4150)(-5275 4300);
WIRE 16 -1 (-5400 4150)(-5275 4150);
WIRE 16 -1 (-5275 4050)(-5275 4150);
WIRE 16 -1 (-5275 4300)(-5400 4300);
WIRE 16 -1 (-5950 5700)(-6725 5700);
FORCEPROP 0 LAST CDS_PHYS_NET_NAME TDR_DIFF_85_NECK_IN1_DN
J 0
(-6685 5740);
PAINT MONO (-6685 5740);
DISPLAY INVISIBLE (-6685 5740);
FORCEPROP 2 LAST SIG_NAME TDR_DIFF_85_NECK_IN1_DN
J 0
(-6710 5660);
DISPLAY 0.638298 (-6710 5660);
PAINT WHITE (-6710 5660);
FORCEPROP 2 LASTPROP $XRERR UNIQUE?
J 0
(-6950 5660);
DISPLAY 0.638298 (-6950 5660);
PAINT MONO (-6950 5660);
DISPLAY INVISIBLE (-6950 5660);
WIRE 16 -1 (-5950 5850)(-6725 5850);
FORCEPROP 0 LAST CDS_PHYS_NET_NAME TDR_DIFF_85_NECK_IN1_DP
J 0
(-6685 5890);
PAINT MONO (-6685 5890);
DISPLAY INVISIBLE (-6685 5890);
FORCEPROP 2 LAST SIG_NAME TDR_DIFF_85_NECK_IN1_DP
J 0
(-6685 5810);
DISPLAY 0.638298 (-6685 5810);
PAINT WHITE (-6685 5810);
FORCEPROP 2 LASTPROP $XRERR UNIQUE?
J 0
(-6925 5810);
DISPLAY 0.638298 (-6925 5810);
PAINT MONO (-6925 5810);
DISPLAY INVISIBLE (-6925 5810);
WIRE 16 -1 (-5950 4300)(-6725 4300);
FORCEPROP 0 LAST CDS_PHYS_NET_NAME TDR_DIFF_85_NECK_IN3_DP
J 0
(-6685 4340);
PAINT MONO (-6685 4340);
DISPLAY INVISIBLE (-6685 4340);
FORCEPROP 2 LAST SIG_NAME TDR_DIFF_85_NECK_IN3_DP
J 0
(-6685 4260);
DISPLAY 0.638298 (-6685 4260);
PAINT WHITE (-6685 4260);
FORCEPROP 2 LASTPROP $XRERR UNIQUE?
J 0
(-6925 4260);
DISPLAY 0.638298 (-6925 4260);
PAINT MONO (-6925 4260);
DISPLAY INVISIBLE (-6925 4260);
WIRE 16 -1 (-5950 5075)(-6725 5075);
FORCEPROP 0 LAST CDS_PHYS_NET_NAME TDR_DIFF_85_NECK_IN2_DP
J 0
(-6685 5115);
PAINT MONO (-6685 5115);
DISPLAY INVISIBLE (-6685 5115);
FORCEPROP 2 LAST SIG_NAME TDR_DIFF_85_NECK_IN2_DP
J 0
(-6685 5035);
DISPLAY 0.638298 (-6685 5035);
PAINT WHITE (-6685 5035);
FORCEPROP 2 LASTPROP $XRERR UNIQUE?
J 0
(-6925 5035);
DISPLAY 0.638298 (-6925 5035);
PAINT MONO (-6925 5035);
DISPLAY INVISIBLE (-6925 5035);
WIRE 16 -1 (-5950 4925)(-6725 4925);
FORCEPROP 0 LAST CDS_PHYS_NET_NAME TDR_DIFF_85_NECK_IN2_DN
J 0
(-6685 4965);
PAINT MONO (-6685 4965);
DISPLAY INVISIBLE (-6685 4965);
FORCEPROP 2 LAST SIG_NAME TDR_DIFF_85_NECK_IN2_DN
J 0
(-6685 4885);
DISPLAY 0.638298 (-6685 4885);
PAINT WHITE (-6685 4885);
FORCEPROP 2 LASTPROP $XRERR UNIQUE?
J 0
(-6925 4885);
DISPLAY 0.638298 (-6925 4885);
PAINT MONO (-6925 4885);
DISPLAY INVISIBLE (-6925 4885);
WIRE 16 -1 (-5950 4150)(-6725 4150);
FORCEPROP 0 LAST CDS_PHYS_NET_NAME TDR_DIFF_85_NECK_IN3_DN
J 0
(-6685 4190);
PAINT MONO (-6685 4190);
DISPLAY INVISIBLE (-6685 4190);
FORCEPROP 2 LAST SIG_NAME TDR_DIFF_85_NECK_IN3_DN
J 0
(-6685 4110);
DISPLAY 0.638298 (-6685 4110);
PAINT WHITE (-6685 4110);
FORCEPROP 2 LASTPROP $XRERR UNIQUE?
J 0
(-6925 4110);
DISPLAY 0.638298 (-6925 4110);
PAINT MONO (-6925 4110);
DISPLAY INVISIBLE (-6925 4110);
WIRE 16 -1 (-7425 5850)(-7275 5850);
WIRE 16 -1 (-7425 5700)(-7425 5850);
WIRE 16 -1 (-7425 5700)(-7275 5700);
WIRE 16 -1 (-7425 5600)(-7425 5700);
WIRE 16 -1 (-7425 5075)(-7275 5075);
WIRE 16 -1 (-7425 4925)(-7425 5075);
WIRE 16 -1 (-7425 4925)(-7275 4925);
WIRE 16 -1 (-7425 4825)(-7425 4925);
WIRE 16 -1 (-7425 4300)(-7275 4300);
WIRE 16 -1 (-7425 4150)(-7425 4300);
WIRE 16 -1 (-7425 4150)(-7275 4150);
WIRE 16 -1 (-7425 4050)(-7425 4150);
WIRE 16 -1 (-5275 3375)(-5275 3525);
WIRE 16 -1 (-5275 3275)(-5275 3375);
WIRE 16 -1 (-5400 3375)(-5275 3375);
WIRE 16 -1 (-5275 3525)(-5400 3525);
WIRE 16 -1 (-5275 2700)(-5275 2850);
WIRE 16 -1 (-5275 2600)(-5275 2700);
WIRE 16 -1 (-5400 2700)(-5275 2700);
WIRE 16 -1 (-5275 2850)(-5400 2850);
WIRE 16 -1 (-5275 2075)(-5400 2075);
WIRE 16 -1 (-5275 1925)(-5275 2075);
WIRE 16 -1 (-5275 1825)(-5275 1925);
WIRE 16 -1 (-5400 1925)(-5275 1925);
WIRE 16 -1 (-5950 3525)(-6725 3525);
FORCEPROP 0 LAST CDS_PHYS_NET_NAME TDR_DIFF_85_NECK_IN4_DP
J 0
(-6685 3565);
PAINT MONO (-6685 3565);
DISPLAY INVISIBLE (-6685 3565);
FORCEPROP 2 LAST SIG_NAME TDR_DIFF_85_NECK_IN4_DP
J 0
(-6710 3485);
DISPLAY 0.638298 (-6710 3485);
PAINT WHITE (-6710 3485);
FORCEPROP 2 LASTPROP $XRERR UNIQUE?
J 0
(-6950 3485);
DISPLAY 0.638298 (-6950 3485);
PAINT MONO (-6950 3485);
DISPLAY INVISIBLE (-6950 3485);
WIRE 16 -1 (-5950 3375)(-6725 3375);
FORCEPROP 0 LAST CDS_PHYS_NET_NAME TDR_DIFF_85_NECK_IN4_DN
J 0
(-6685 3415);
PAINT MONO (-6685 3415);
DISPLAY INVISIBLE (-6685 3415);
FORCEPROP 2 LAST SIG_NAME TDR_DIFF_85_NECK_IN4_DN
J 0
(-6710 3335);
DISPLAY 0.638298 (-6710 3335);
PAINT WHITE (-6710 3335);
FORCEPROP 2 LASTPROP $XRERR UNIQUE?
J 0
(-6950 3335);
DISPLAY 0.638298 (-6950 3335);
PAINT MONO (-6950 3335);
DISPLAY INVISIBLE (-6950 3335);
WIRE 16 -1 (-5950 2850)(-6725 2850);
FORCEPROP 0 LAST CDS_PHYS_NET_NAME TDR_DIFF_85_NECK_IN5_DP
J 0
(-6685 2890);
PAINT MONO (-6685 2890);
DISPLAY INVISIBLE (-6685 2890);
FORCEPROP 2 LAST SIG_NAME TDR_DIFF_85_NECK_IN5_DP
J 0
(-6685 2810);
DISPLAY 0.638298 (-6685 2810);
PAINT WHITE (-6685 2810);
FORCEPROP 2 LASTPROP $XRERR UNIQUE?
J 0
(-6925 2810);
DISPLAY 0.638298 (-6925 2810);
PAINT MONO (-6925 2810);
DISPLAY INVISIBLE (-6925 2810);
WIRE 16 -1 (-5950 2700)(-6725 2700);
FORCEPROP 0 LAST CDS_PHYS_NET_NAME TDR_DIFF_85_NECK_IN5_DN
J 0
(-6685 2740);
PAINT MONO (-6685 2740);
DISPLAY INVISIBLE (-6685 2740);
FORCEPROP 2 LAST SIG_NAME TDR_DIFF_85_NECK_IN5_DN
J 0
(-6710 2660);
DISPLAY 0.638298 (-6710 2660);
PAINT WHITE (-6710 2660);
FORCEPROP 2 LASTPROP $XRERR UNIQUE?
J 0
(-6950 2660);
DISPLAY 0.638298 (-6950 2660);
PAINT MONO (-6950 2660);
DISPLAY INVISIBLE (-6950 2660);
WIRE 16 -1 (-5950 1925)(-6725 1925);
FORCEPROP 0 LAST CDS_PHYS_NET_NAME TDR_DIFF_85_NECK_IN6_DN
J 0
(-6685 1965);
PAINT MONO (-6685 1965);
DISPLAY INVISIBLE (-6685 1965);
FORCEPROP 2 LAST SIG_NAME TDR_DIFF_85_NECK_IN6_DN
J 0
(-6685 1885);
DISPLAY 0.638298 (-6685 1885);
PAINT WHITE (-6685 1885);
FORCEPROP 2 LASTPROP $XRERR UNIQUE?
J 0
(-6925 1885);
DISPLAY 0.638298 (-6925 1885);
PAINT MONO (-6925 1885);
DISPLAY INVISIBLE (-6925 1885);
WIRE 16 -1 (-5950 2075)(-6725 2075);
FORCEPROP 0 LAST CDS_PHYS_NET_NAME TDR_DIFF_85_NECK_IN6_DP
J 0
(-6685 2115);
PAINT MONO (-6685 2115);
DISPLAY INVISIBLE (-6685 2115);
FORCEPROP 2 LAST SIG_NAME TDR_DIFF_85_NECK_IN6_DP
J 0
(-6685 2035);
DISPLAY 0.638298 (-6685 2035);
PAINT WHITE (-6685 2035);
FORCEPROP 2 LASTPROP $XRERR UNIQUE?
J 0
(-6925 2035);
DISPLAY 0.638298 (-6925 2035);
PAINT MONO (-6925 2035);
DISPLAY INVISIBLE (-6925 2035);
WIRE 16 -1 (-7425 3525)(-7275 3525);
WIRE 16 -1 (-7425 3375)(-7425 3525);
WIRE 16 -1 (-7425 3375)(-7275 3375);
WIRE 16 -1 (-7425 3275)(-7425 3375);
WIRE 16 -1 (-7425 2850)(-7275 2850);
WIRE 16 -1 (-7425 2700)(-7425 2850);
WIRE 16 -1 (-7425 2700)(-7275 2700);
WIRE 16 -1 (-7425 2600)(-7425 2700);
WIRE 16 -1 (-7425 2075)(-7275 2075);
WIRE 16 -1 (-7425 1925)(-7425 2075);
WIRE 16 -1 (-7425 1925)(-7275 1925);
WIRE 16 -1 (-7425 1825)(-7425 1925);
DOT 1 (-7425 1925);
DOT 1 (-7425 2700);
DOT 1 (-7425 3375);
DOT 1 (-5275 1925);
DOT 1 (-5275 2700);
DOT 1 (-5275 3375);
DOT 1 (-7425 4150);
DOT 1 (-7425 4925);
DOT 1 (-7425 5700);
DOT 1 (-5275 4150);
DOT 1 (-5275 4925);
DOT 1 (-5275 5700);
FORCENOTE
85 OHM NECK
(-7125 6350) 0;
DISPLAY LEFT (-7125 6350);
DISPLAY 3.148936 (-7125 6350);
PAINT WHITE (-7125 6350);
QUIT
